# S9S_MB_2U (Grand Teton) — schematic netlist excerpt (pin names and nets, part order shuffled) for the footprints in the layout excerpt that follows; sources: Cadence DE-HDL packaged netlist, KiCad conversion of 03242023_DA0F0TMBIJ0_F0T_Motherboard_J_brd_V01_OCP.brd

PR1792  Q_RES  3.3 1% CHIP  pkg 0402LF  page 288 : A = SW_PVCCIN_CPU1_BOOT8 ; B = SW_PVCCIN_CPU1_BOOT8_R
C3268  Q_CAP  1000PF 50V 5% X7R  pkg 0402  page 266 : A = PVCCFA_EHV_FIVRA_CPU0_EN_R ; B = GND

(kicad_pcb
	(version 20260206)
	(generator "pcbnew")
	(generator_version "10.0")
	(general
		(thickness 1.6)
		(legacy_teardrops no)
	)
	(paper "A4")
	(title_block
		(title "03242023_DA0F0TMBIJ0_F0T_Motherboard_J_brd_V01_OCP.brd")
		(comment 1 "Grand Teton / footprints 614-615 of 6105")
	)
	(layers
		(0 "F.Cu" signal "TOP")
		(4 "In1.Cu" signal "GND")
		(6 "In2.Cu" signal "IN1")
		(8 "In3.Cu" signal "GND1")
		(10 "In4.Cu" signal "IN2")
		(12 "In5.Cu" signal "GND2")
		(14 "In6.Cu" signal "IN3")
		(16 "In7.Cu" signal "GND3")
		(18 "In8.Cu" signal "VCC")
		(20 "In9.Cu" signal "VCC1")
		(22 "In10.Cu" signal "GND4")
		(24 "In11.Cu" signal "IN4")
		(26 "In12.Cu" signal "GND5")
		(28 "In13.Cu" signal "IN5")
		(30 "In14.Cu" signal "GND6")
		(32 "In15.Cu" signal "IN6")
		(34 "In16.Cu" signal "GND7")
		(2 "B.Cu" signal "BOTTOM")
		(9 "F.Adhes" user "F.Adhesive")
		(11 "B.Adhes" user "B.Adhesive")
		(13 "F.Paste" user "Package Geometry/Pastemask Top")
		(15 "B.Paste" user "Package Geometry/Pastemask Bottom")
		(5 "F.SilkS" user "Ref Des/Silkscreen Top")
		(7 "B.SilkS" user "Ref Des/Silkscreen Bottom")
		(1 "F.Mask" user "Board Geometry/Soldermask Top")
		(3 "B.Mask" user "Board Geometry/Soldermask Bottom")
		(17 "Dwgs.User" user "User.Drawings")
		(19 "Cmts.User" user "User.Comments")
		(21 "Eco1.User" user "User.Eco1")
		(23 "Eco2.User" user "User.Eco2")
		(25 "Edge.Cuts" user "Board Geometry/Outline")
		(27 "Margin" user)
		(31 "F.CrtYd" user "Package Geometry/Place Bound Top")
		(29 "B.CrtYd" user "Package Geometry/Place Bound Bottom")
		(35 "F.Fab" user "Ref Des/Assembly Top")
		(33 "B.Fab" user "Ref Des/Assembly Bottom")
	)
	(footprint ""
		(layer "F.Cu")
		(at 138.55954 -347.520514 90)
		(property "Reference" "PR1792"
			(at 0 0 90)
			(layer "F.SilkS")
			(hide yes)
			(effects
				(font
					(size 1.27 1.27)
				)
			)
		)
		(property "Value" ""
			(at 0 0 90)
			(layer "F.Fab")
			(effects
				(font
					(size 1.27 1.27)
				)
			)
		)
		(duplicate_pad_numbers_are_jumpers no)
		(fp_line
			(start 0.7874 -0.4064)
			(end 0.7874 0.4064)
			(stroke
				(width 0.1524)
				(type default)
			)
			(layer "F.SilkS")
		)
		(fp_line
			(start -0.7874 -0.4064)
			(end 0.7874 -0.4064)
			(stroke
				(width 0.1524)
				(type default)
			)
			(layer "F.SilkS")
		)
		(fp_line
			(start 0.7874 0.4064)
			(end -0.7874 0.4064)
			(stroke
				(width 0.1524)
				(type default)
			)
			(layer "F.SilkS")
		)
		(fp_line
			(start -0.7874 0.4064)
			(end -0.7874 -0.4064)
			(stroke
				(width 0.1524)
				(type default)
			)
			(layer "F.SilkS")
		)
		(fp_line
			(start -0.12065 -0.305054)
			(end -0.12065 -0.2794)
			(stroke
				(width 0.1)
				(type default)
			)
			(layer "F.Fab")
		)
		(fp_line
			(start -0.67945 -0.305054)
			(end -0.12065 -0.305054)
			(stroke
				(width 0.1)
				(type default)
			)
			(layer "F.Fab")
		)
		(fp_line
			(start 0.67945 -0.3048)
			(end 0.67945 0.3048)
			(stroke
				(width 0.1)
				(type default)
			)
			(layer "F.Fab")
		)
		(fp_line
			(start 0.12065 -0.3048)
			(end 0.67945 -0.3048)
			(stroke
				(width 0.1)
				(type default)
			)
			(layer "F.Fab")
		)
		(fp_line
			(start 0.12065 -0.2794)
			(end 0.12065 -0.3048)
			(stroke
				(width 0.1)
				(type default)
			)
			(layer "F.Fab")
		)
		(fp_line
			(start -0.12065 -0.2794)
			(end 0.12065 -0.2794)
			(stroke
				(width 0.1)
				(type default)
			)
			(layer "F.Fab")
		)
		(fp_line
			(start 0.120396 0.2794)
			(end -0.12065 0.2794)
			(stroke
				(width 0.1)
				(type default)
			)
			(layer "F.Fab")
		)
		(fp_line
			(start -0.12065 0.2794)
			(end -0.12065 0.3048)
			(stroke
				(width 0.1)
				(type default)
			)
			(layer "F.Fab")
		)
		(fp_line
			(start 0.67945 0.3048)
			(end 0.120396 0.3048)
			(stroke
				(width 0.1)
				(type default)
			)
			(layer "F.Fab")
		)
		(fp_line
			(start 0.120396 0.3048)
			(end 0.120396 0.2794)
			(stroke
				(width 0.1)
				(type default)
			)
			(layer "F.Fab")
		)
		(fp_line
			(start -0.12065 0.3048)
			(end -0.67945 0.3048)
			(stroke
				(width 0.1)
				(type default)
			)
			(layer "F.Fab")
		)
		(fp_line
			(start -0.67945 0.3048)
			(end -0.67945 -0.305054)
			(stroke
				(width 0.1)
				(type default)
			)
			(layer "F.Fab")
		)
		(pad "1" smd circle
			(at -0.40005 0 90)
			(size 0 0)
			(layers "F.Cu" "F.Mask" "F.Paste")
			(net "SW_PVCCIN_CPU1_BOOT8")
		)
		(pad "2" smd circle
			(at 0.40005 0 90)
			(size 0 0)
			(layers "F.Cu" "F.Mask" "F.Paste")
			(net "SW_PVCCIN_CPU1_BOOT8_R")
		)
	)
	(footprint ""
		(layer "F.Cu")
		(at 352.089974 -354.495862 -90)
		(property "Reference" "C3268"
			(at 0 0 270)
			(layer "F.SilkS")
			(hide yes)
			(effects
				(font
					(size 1.27 1.27)
				)
			)
		)
		(property "Value" ""
			(at 0 0 270)
			(layer "F.Fab")
			(effects
				(font
					(size 1.27 1.27)
				)
			)
		)
		(duplicate_pad_numbers_are_jumpers no)
		(fp_line
			(start -0.7874 0.4064)
			(end -0.7874 -0.4064)
			(stroke
				(width 0.1524)
				(type default)
			)
			(layer "F.SilkS")
		)
		(fp_line
			(start 0.7874 0.4064)
			(end -0.7874 0.4064)
			(stroke
				(width 0.1524)
				(type default)
			)
			(layer "F.SilkS")
		)
		(fp_line
			(start -0.7874 -0.4064)
			(end 0.7874 -0.4064)
			(stroke
				(width 0.1524)
				(type default)
			)
			(layer "F.SilkS")
		)
		(fp_line
			(start 0.7874 -0.4064)
			(end 0.7874 0.4064)
			(stroke
				(width 0.1524)
				(type default)
			)
			(layer "F.SilkS")
		)
		(fp_line
			(start -0.67945 0.3048)
			(end -0.67945 -0.305054)
			(stroke
				(width 0.1)
				(type default)
			)
			(layer "F.Fab")
		)
		(fp_line
			(start -0.12065 0.3048)
			(end -0.67945 0.3048)
			(stroke
				(width 0.1)
				(type default)
			)
			(layer "F.Fab")
		)
		(fp_line
			(start 0.120396 0.3048)
			(end 0.120396 0.2794)
			(stroke
				(width 0.1)
				(type default)
			)
			(layer "F.Fab")
		)
		(fp_line
			(start 0.67945 0.3048)
			(end 0.120396 0.3048)
			(stroke
				(width 0.1)
				(type default)
			)
			(layer "F.Fab")
		)
		(fp_line
			(start -0.12065 0.2794)
			(end -0.12065 0.3048)
			(stroke
				(width 0.1)
				(type default)
			)
			(layer "F.Fab")
		)
		(fp_line
			(start 0.120396 0.2794)
			(end -0.12065 0.2794)
			(stroke
				(width 0.1)
				(type default)
			)
			(layer "F.Fab")
		)
		(fp_line
			(start -0.12065 -0.2794)
			(end 0.12065 -0.2794)
			(stroke
				(width 0.1)
				(type default)
			)
			(layer "F.Fab")
		)
		(fp_line
			(start 0.12065 -0.2794)
			(end 0.12065 -0.3048)
			(stroke
				(width 0.1)
				(type default)
			)
			(layer "F.Fab")
		)
		(fp_line
			(start 0.12065 -0.3048)
			(end 0.67945 -0.3048)
			(stroke
				(width 0.1)
				(type default)
			)
			(layer "F.Fab")
		)
		(fp_line
			(start 0.67945 -0.3048)
			(end 0.67945 0.3048)
			(stroke
				(width 0.1)
				(type default)
			)
			(layer "F.Fab")
		)
		(fp_line
			(start -0.67945 -0.305054)
			(end -0.12065 -0.305054)
			(stroke
				(width 0.1)
				(type default)
			)
			(layer "F.Fab")
		)
		(fp_line
			(start -0.12065 -0.305054)
			(end -0.12065 -0.2794)
			(stroke
				(width 0.1)
				(type default)
			)
			(layer "F.Fab")
		)
		(pad "1" smd circle
			(at -0.40005 0 270)
			(size 0 0)
			(layers "F.Cu" "F.Mask" "F.Paste")
			(net "PVCCFA_EHV_FIVRA_CPU0_EN_R")
		)
		(pad "2" smd circle
			(at 0.40005 0 270)
			(size 0 0)
			(layers "F.Cu" "F.Mask" "F.Paste")
			(net "GND")
		)
	)
)
